(kicad_pcb
	(version 20260206)
	(generator "pcbnew")
	(generator_version "10.0")
	(general
		(thickness 1.6)
		(legacy_teardrops no)
	)
	(paper "A4")
	(title_block
		(title "timecard-production-celestica-r4006 — R4006-B0001-02_R01.brd")
		(comment 1 "Time Appliance Project (Time Card) / footprints 935-939 of 1113")
	)
	(layers
		(0 "F.Cu" signal "TOP")
		(4 "In1.Cu" signal "L02_GND1")
		(6 "In2.Cu" signal "L03_SIG1")
		(8 "In3.Cu" signal "L04_GND2")
		(10 "In4.Cu" signal "L05_VCC1")
		(12 "In5.Cu" signal "L06_VCC2")
		(14 "In6.Cu" signal "L07_GND3")
		(16 "In7.Cu" signal "L08_SIG2")
		(18 "In8.Cu" signal "L09_GND4")
		(2 "B.Cu" signal "BOTTOM")
		(9 "F.Adhes" user "F.Adhesive")
		(11 "B.Adhes" user "B.Adhesive")
		(13 "F.Paste" user "Package Geometry/Pastemask Top")
		(15 "B.Paste" user "Package Geometry/Pastemask Bottom")
		(5 "F.SilkS" user "Ref Des/Silkscreen Top")
		(7 "B.SilkS" user "Ref Des/Silkscreen Bottom")
		(1 "F.Mask" user "Board Geometry/Soldermask Top")
		(3 "B.Mask" user "Board Geometry/Soldermask Bottom")
		(17 "Dwgs.User" user "User.Drawings")
		(19 "Cmts.User" user "User.Comments")
		(21 "Eco1.User" user "User.Eco1")
		(23 "Eco2.User" user "User.Eco2")
		(25 "Edge.Cuts" user "Board Geometry/Outline")
		(27 "Margin" user)
		(31 "F.CrtYd" user "Package Geometry/Place Bound Top")
		(29 "B.CrtYd" user "Package Geometry/Place Bound Bottom")
		(35 "F.Fab" user "Ref Des/Assembly Top")
		(33 "B.Fab" user "Ref Des/Assembly Bottom")
	)
	(footprint ""
		(layer "B.Cu")
		(at 105.8418 -74.5744)
		(property "Reference" "C241"
			(at -3.81 -0.08763 0)
			(unlocked yes)
			(layer "B.SilkS")
			(effects
				(font
					(size 0.7874 0.5842)
					(thickness 0.1524)
				)
				(justify mirror)
			)
		)
		(property "Value" "VAL*"
			(at -0.0762 3.134106 0)
			(unlocked yes)
			(layer "B.Fab")
			(hide yes)
			(effects
				(font
					(size 0.7874 0.5842)
					(thickness 0.1524)
				)
				(justify mirror)
			)
		)
		(property "Device Type" "CAPACITOR-G107-0F226-CM,22UF,2A"
			(at -0.0508 2.194306 0)
			(unlocked yes)
			(layer "B.Fab")
			(hide yes)
			(effects
				(font
					(size 0.7874 0.5842)
					(thickness 0.1524)
				)
				(justify mirror)
			)
		)
		(property "User Part Number" "PARTNUM*"
			(at -0.1016 5.013706 0)
			(unlocked yes)
			(layer "Cmts.User")
			(hide yes)
			(effects
				(font
					(size 0.7874 0.5842)
					(thickness 0.1524)
				)
				(justify mirror)
			)
		)
		(property "Tolerance" "TOL*"
			(at -0.0762 4.048506 0)
			(unlocked yes)
			(layer "Cmts.User")
			(hide yes)
			(effects
				(font
					(size 0.7874 0.5842)
					(thickness 0.1524)
				)
				(justify mirror)
			)
		)
		(duplicate_pad_numbers_are_jumpers no)
		(fp_line
			(start -1.5748 -0.9398)
			(end 1.5748 -0.9398)
			(stroke
				(width 0.1)
				(type default)
			)
			(layer "B.SilkS")
		)
		(fp_line
			(start -1.5748 0.9398)
			(end -1.5748 -0.9398)
			(stroke
				(width 0.1)
				(type default)
			)
			(layer "B.SilkS")
		)
		(fp_line
			(start 1.5748 -0.9398)
			(end 1.5748 0.9398)
			(stroke
				(width 0.1)
				(type default)
			)
			(layer "B.SilkS")
		)
		(fp_line
			(start 1.5748 0.9398)
			(end -1.5748 0.9398)
			(stroke
				(width 0.1)
				(type default)
			)
			(layer "B.SilkS")
		)
		(fp_rect
			(start 1.5748 -0.9398)
			(end -1.5748 0.9398)
			(stroke
				(width 0)
				(type default)
			)
			(fill no)
			(layer "B.CrtYd")
		)
		(fp_line
			(start -1.016 -0.635)
			(end 1.016 -0.635)
			(stroke
				(width 0.1)
				(type default)
			)
			(layer "B.Fab")
		)
		(fp_line
			(start -1.016 0.635)
			(end -1.016 -0.635)
			(stroke
				(width 0.1)
				(type default)
			)
			(layer "B.Fab")
		)
		(fp_line
			(start 1.016 -0.635)
			(end 1.016 0.635)
			(stroke
				(width 0.1)
				(type default)
			)
			(layer "B.Fab")
		)
		(fp_line
			(start 1.016 0.635)
			(end -1.016 0.635)
			(stroke
				(width 0.1)
				(type default)
			)
			(layer "B.Fab")
		)
		(pad "1" smd rect
			(at 0.8382 0 180)
			(size 0.9652 1.3716)
			(layers "B.Cu" "B.Mask" "B.Paste")
			(net "XP3R3V_FPGA")
		)
		(pad "2" smd rect
			(at -0.8382 0 180)
			(size 0.9652 1.3716)
			(layers "B.Cu" "B.Mask" "B.Paste")
			(net "SG")
		)
		(zone
			(layer "B.Cu")
			(hatch none 0.5)
			(connect_pads
				(clearance 0)
			)
			(min_thickness 0.25)
			(keepout
				(tracks allowed)
				(vias not_allowed)
				(pads allowed)
				(copperpour not_allowed)
				(footprints allowed)
			)
			(placement
				(enabled no)
				(sheetname "")
			)
			(fill
				(thermal_gap 0.5)
				(thermal_bridge_width 0.5)
				(island_removal_mode 0)
			)
			(polygon
				(pts
					(xy 106.0704 -75.2094) (xy 105.6132 -75.2094) (xy 105.6132 -73.9394) (xy 106.0704 -73.9394)
				)
			)
		)
	)
	(footprint ""
		(layer "B.Cu")
		(at 92.202 -55.118 180)
		(property "Reference" "C150"
			(at -0.508 -1.94437 0)
			(unlocked yes)
			(layer "B.SilkS")
			(effects
				(font
					(size 0.7874 0.5842)
					(thickness 0.1524)
				)
				(justify mirror)
			)
		)
		(property "Value" "VAL*"
			(at -0.0762 2.067306 180)
			(unlocked yes)
			(layer "B.Fab")
			(hide yes)
			(effects
				(font
					(size 0.7874 0.5842)
					(thickness 0.1524)
				)
				(justify mirror)
			)
		)
		(property "Device Type" "CAPACITOR-G105-0B104-CK,0.1UF,A"
			(at -0.0508 1.127506 180)
			(unlocked yes)
			(layer "B.Fab")
			(hide yes)
			(effects
				(font
					(size 0.7874 0.5842)
					(thickness 0.1524)
				)
				(justify mirror)
			)
		)
		(property "User Part Number" "PARTNUM*"
			(at -0.1016 4.023106 180)
			(unlocked yes)
			(layer "Cmts.User")
			(hide yes)
			(effects
				(font
					(size 0.7874 0.5842)
					(thickness 0.1524)
				)
				(justify mirror)
			)
		)
		(property "Tolerance" "TOL*"
			(at -0.0762 3.032506 180)
			(unlocked yes)
			(layer "Cmts.User")
			(hide yes)
			(effects
				(font
					(size 0.7874 0.5842)
					(thickness 0.1524)
				)
				(justify mirror)
			)
		)
		(duplicate_pad_numbers_are_jumpers no)
		(fp_line
			(start 1.143 0.5588)
			(end -1.143 0.5588)
			(stroke
				(width 0.1)
				(type default)
			)
			(layer "B.SilkS")
		)
		(fp_line
			(start 1.143 -0.5588)
			(end 1.143 0.5588)
			(stroke
				(width 0.1)
				(type default)
			)
			(layer "B.SilkS")
		)
		(fp_line
			(start -1.143 0.5588)
			(end -1.143 -0.5588)
			(stroke
				(width 0.1)
				(type default)
			)
			(layer "B.SilkS")
		)
		(fp_line
			(start -1.143 -0.5588)
			(end 1.143 -0.5588)
			(stroke
				(width 0.1)
				(type default)
			)
			(layer "B.SilkS")
		)
		(fp_rect
			(start -1.143 0.5588)
			(end 1.143 -0.5588)
			(stroke
				(width 0)
				(type default)
			)
			(fill no)
			(layer "B.CrtYd")
		)
		(fp_line
			(start 0.508 0.3048)
			(end -0.508 0.3048)
			(stroke
				(width 0.1)
				(type default)
			)
			(layer "B.Fab")
		)
		(fp_line
			(start 0.508 -0.3048)
			(end 0.508 0.3048)
			(stroke
				(width 0.1)
				(type default)
			)
			(layer "B.Fab")
		)
		(fp_line
			(start -0.508 0.3048)
			(end -0.508 -0.3048)
			(stroke
				(width 0.1)
				(type default)
			)
			(layer "B.Fab")
		)
		(fp_line
			(start -0.508 -0.3048)
			(end 0.508 -0.3048)
			(stroke
				(width 0.1)
				(type default)
			)
			(layer "B.Fab")
		)
		(pad "1" smd rect
			(at 0.5334 0)
			(size 0.7112 0.6096)
			(layers "B.Cu" "B.Mask" "B.Paste")
			(net "XP1R8V_FPGA")
		)
		(pad "2" smd rect
			(at -0.5334 0)
			(size 0.7112 0.6096)
			(layers "B.Cu" "B.Mask" "B.Paste")
			(net "SG")
		)
		(zone
			(layer "B.Cu")
			(hatch none 0.5)
			(connect_pads
				(clearance 0)
			)
			(min_thickness 0.25)
			(keepout
				(tracks allowed)
				(vias not_allowed)
				(pads allowed)
				(copperpour not_allowed)
				(footprints allowed)
			)
			(placement
				(enabled no)
				(sheetname "")
			)
			(fill
				(thermal_gap 0.5)
				(thermal_bridge_width 0.5)
				(island_removal_mode 0)
			)
			(polygon
				(pts
					(xy 92.2782 -55.4228) (xy 92.1258 -55.4228) (xy 92.1258 -54.8132) (xy 92.2782 -54.8132)
				)
			)
		)
	)
	(footprint ""
		(layer "B.Cu")
		(at 100.84689 -37.323268 -90)
		(property "Reference" "C217"
			(at 1.524508 42.01922 270)
			(unlocked yes)
			(layer "B.SilkS")
			(effects
				(font
					(size 0.635 0.4064)
					(thickness 0.1524)
				)
				(justify mirror)
			)
		)
		(property "Value" "VAL*"
			(at 0 3.718306 270)
			(unlocked yes)
			(layer "B.Fab")
			(hide yes)
			(effects
				(font
					(size 0.7874 0.5842)
					(thickness 0.127)
				)
				(justify mirror)
			)
		)
		(property "Tolerance" "TOL*"
			(at 0 4.861306 270)
			(unlocked yes)
			(layer "Cmts.User")
			(hide yes)
			(effects
				(font
					(size 0.7874 0.5842)
					(thickness 0.127)
				)
				(justify mirror)
			)
		)
		(property "User Part Number" "PARTNUM*"
			(at 0 2.575306 270)
			(unlocked yes)
			(layer "Cmts.User")
			(hide yes)
			(effects
				(font
					(size 0.7874 0.5842)
					(thickness 0.127)
				)
				(justify mirror)
			)
		)
		(property "Device Type" "CAPACITOR-G105-0B104-CK,0.1UF,A"
			(at 0 1.432306 270)
			(unlocked yes)
			(layer "B.Fab")
			(hide yes)
			(effects
				(font
					(size 0.7874 0.5842)
					(thickness 0.127)
				)
				(justify mirror)
			)
		)
		(duplicate_pad_numbers_are_jumpers no)
		(fp_line
			(start -0.970026 0.4699)
			(end 0.970026 0.4699)
			(stroke
				(width 0.1)
				(type default)
			)
			(layer "B.SilkS")
		)
		(fp_line
			(start 0.970026 0.4699)
			(end 0.970026 -0.4699)
			(stroke
				(width 0.1)
				(type default)
			)
			(layer "B.SilkS")
		)
		(fp_line
			(start -0.970026 -0.4699)
			(end -0.970026 0.4699)
			(stroke
				(width 0.1)
				(type default)
			)
			(layer "B.SilkS")
		)
		(fp_line
			(start 0.970026 -0.4699)
			(end -0.970026 -0.4699)
			(stroke
				(width 0.1)
				(type default)
			)
			(layer "B.SilkS")
		)
		(fp_poly
			(pts
				(xy 0.970026 0.4699) (xy -0.970026 0.4699) (xy -0.970026 -0.4699) (xy 0.970026 -0.4699)
			)
			(stroke
				(width 0)
				(type default)
			)
			(fill no)
			(layer "B.CrtYd")
		)
		(fp_line
			(start -0.508 0.3048)
			(end 0.508 0.3048)
			(stroke
				(width 0.1)
				(type default)
			)
			(layer "B.Fab")
		)
		(fp_line
			(start 0.508 0.3048)
			(end 0.508 -0.3048)
			(stroke
				(width 0.1)
				(type default)
			)
			(layer "B.Fab")
		)
		(fp_line
			(start -0.508 -0.3048)
			(end -0.508 0.3048)
			(stroke
				(width 0.1)
				(type default)
			)
			(layer "B.Fab")
		)
		(fp_line
			(start 0.508 -0.3048)
			(end -0.508 -0.3048)
			(stroke
				(width 0.1)
				(type default)
			)
			(layer "B.Fab")
		)
		(pad "1" smd circle
			(at 0.500126 0 90)
			(size 0.635 0.635)
			(layers "B.Cu" "B.Mask" "B.Paste")
			(net "FPGA_MGTAVTT")
		)
		(pad "2" smd circle
			(at -0.500126 0 90)
			(size 0.635 0.635)
			(layers "B.Cu" "B.Mask" "B.Paste")
			(net "SG")
		)
	)
	(footprint ""
		(layer "B.Cu")
		(at 107.823 -104.521 180)
		(property "Reference" "R318"
			(at -0.127 2.88163 0)
			(unlocked yes)
			(layer "B.SilkS")
			(effects
				(font
					(size 0.7874 0.5842)
					(thickness 0.1524)
				)
				(justify mirror)
			)
		)
		(property "Value" "VAL*"
			(at -0.02032 2.13233 180)
			(unlocked yes)
			(layer "B.Fab")
			(hide yes)
			(effects
				(font
					(size 0.7874 0.5842)
					(thickness 0.1524)
				)
				(justify mirror)
			)
		)
		(property "Tolerance" "TOL*"
			(at -0.044704 3.05435 180)
			(unlocked yes)
			(layer "Cmts.User")
			(hide yes)
			(effects
				(font
					(size 0.7874 0.5842)
					(thickness 0.1524)
				)
				(justify mirror)
			)
		)
		(property "User Part Number" "PARTNUM*"
			(at -0.02032 4.024884 180)
			(unlocked yes)
			(layer "Cmts.User")
			(hide yes)
			(effects
				(font
					(size 0.7874 0.5842)
					(thickness 0.1524)
				)
				(justify mirror)
			)
		)
		(property "Device Type" "RESISTOR-G155-11002-01,10KOHM,A"
			(at -0.008382 1.210564 180)
			(unlocked yes)
			(layer "B.Fab")
			(hide yes)
			(effects
				(font
					(size 0.7874 0.5842)
					(thickness 0.1524)
				)
				(justify mirror)
			)
		)
		(duplicate_pad_numbers_are_jumpers no)
		(fp_line
			(start 1.143 0.5588)
			(end -1.143 0.5588)
			(stroke
				(width 0.1)
				(type default)
			)
			(layer "B.SilkS")
		)
		(fp_line
			(start 1.143 -0.5588)
			(end 1.143 0.5588)
			(stroke
				(width 0.1)
				(type default)
			)
			(layer "B.SilkS")
		)
		(fp_line
			(start -1.143 0.5588)
			(end -1.143 -0.5588)
			(stroke
				(width 0.1)
				(type default)
			)
			(layer "B.SilkS")
		)
		(fp_line
			(start -1.143 -0.5588)
			(end 1.143 -0.5588)
			(stroke
				(width 0.1)
				(type default)
			)
			(layer "B.SilkS")
		)
		(fp_poly
			(pts
				(xy 1.143 0.5588) (xy -1.143 0.5588) (xy -1.143 -0.5588) (xy 1.143 -0.5588)
			)
			(stroke
				(width 0)
				(type default)
			)
			(fill no)
			(layer "B.CrtYd")
		)
		(fp_line
			(start 0.508 0.3048)
			(end -0.508 0.3048)
			(stroke
				(width 0.1)
				(type default)
			)
			(layer "B.Fab")
		)
		(fp_line
			(start 0.508 -0.3048)
			(end 0.508 0.3048)
			(stroke
				(width 0.1)
				(type default)
			)
			(layer "B.Fab")
		)
		(fp_line
			(start -0.508 0.3048)
			(end -0.508 -0.3048)
			(stroke
				(width 0.1)
				(type default)
			)
			(layer "B.Fab")
		)
		(fp_line
			(start -0.508 -0.3048)
			(end 0.508 -0.3048)
			(stroke
				(width 0.1)
				(type default)
			)
			(layer "B.Fab")
		)
		(pad "1" smd rect
			(at 0.5334 0)
			(size 0.7112 0.6096)
			(layers "B.Cu" "B.Mask" "B.Paste")
			(net "XP3R3V_FPGA")
		)
		(pad "2" smd rect
			(at -0.5334 0)
			(size 0.7112 0.6096)
			(layers "B.Cu" "B.Mask" "B.Paste")
			(net "R_RGB_LED_I2C_SCL")
		)
		(zone
			(layer "B.Cu")
			(hatch none 0.5)
			(connect_pads
				(clearance 0)
			)
			(min_thickness 0.25)
			(keepout
				(tracks not_allowed)
				(vias allowed)
				(pads allowed)
				(copperpour not_allowed)
				(footprints allowed)
			)
			(placement
				(enabled no)
				(sheetname "")
			)
			(fill
				(thermal_gap 0.5)
				(thermal_bridge_width 0.5)
				(island_removal_mode 0)
			)
			(polygon
				(pts
					(xy 107.7468 -104.8258) (xy 107.7468 -104.2162) (xy 107.8992 -104.2162) (xy 107.8992 -104.8258)
				)
			)
		)
		(zone
			(layer "B.Cu")
			(hatch none 0.5)
			(connect_pads
				(clearance 0)
			)
			(min_thickness 0.25)
			(keepout
				(tracks allowed)
				(vias not_allowed)
				(pads allowed)
				(copperpour not_allowed)
				(footprints allowed)
			)
			(placement
				(enabled no)
				(sheetname "")
			)
			(fill
				(thermal_gap 0.5)
				(thermal_bridge_width 0.5)
				(island_removal_mode 0)
			)
			(polygon
				(pts
					(xy 107.7468 -104.8258) (xy 107.7468 -104.2162) (xy 107.8992 -104.2162) (xy 107.8992 -104.8258)
				)
			)
		)
	)
	(footprint ""
		(layer "B.Cu")
		(at 150.343108 -49.01311 -90)
		(property "Reference" "R64"
			(at -3.81889 0.776478 270)
			(unlocked yes)
			(layer "B.SilkS")
			(effects
				(font
					(size 0.7874 0.5842)
					(thickness 0.1524)
				)
				(justify mirror)
			)
		)
		(property "Value" "VAL*"
			(at -0.02032 2.13233 270)
			(unlocked yes)
			(layer "B.Fab")
			(hide yes)
			(effects
				(font
					(size 0.7874 0.5842)
					(thickness 0.1524)
				)
				(justify mirror)
			)
		)
		(property "Device Type" "RESISTOR-G155-14701-01,4.7KOHMA"
			(at -0.008382 1.210564 270)
			(unlocked yes)
			(layer "B.Fab")
			(hide yes)
			(effects
				(font
					(size 0.7874 0.5842)
					(thickness 0.1524)
				)
				(justify mirror)
			)
		)
		(property "User Part Number" "PARTNUM*"
			(at -0.02032 4.024884 270)
			(unlocked yes)
			(layer "Cmts.User")
			(hide yes)
			(effects
				(font
					(size 0.7874 0.5842)
					(thickness 0.1524)
				)
				(justify mirror)
			)
		)
		(property "Tolerance" "TOL*"
			(at -0.044704 3.05435 270)
			(unlocked yes)
			(layer "Cmts.User")
			(hide yes)
			(effects
				(font
					(size 0.7874 0.5842)
					(thickness 0.1524)
				)
				(justify mirror)
			)
		)
		(duplicate_pad_numbers_are_jumpers no)
		(fp_line
			(start -1.143 0.5588)
			(end -1.143 -0.5588)
			(stroke
				(width 0.1)
				(type default)
			)
			(layer "B.SilkS")
		)
		(fp_line
			(start 1.143 0.5588)
			(end -1.143 0.5588)
			(stroke
				(width 0.1)
				(type default)
			)
			(layer "B.SilkS")
		)
		(fp_line
			(start -1.143 -0.5588)
			(end 1.143 -0.5588)
			(stroke
				(width 0.1)
				(type default)
			)
			(layer "B.SilkS")
		)
		(fp_line
			(start 1.143 -0.5588)
			(end 1.143 0.5588)
			(stroke
				(width 0.1)
				(type default)
			)
			(layer "B.SilkS")
		)
		(fp_rect
			(start 1.143 0.5588)
			(end -1.143 -0.5588)
			(stroke
				(width 0)
				(type default)
			)
			(fill no)
			(layer "B.CrtYd")
		)
		(fp_line
			(start -0.508 0.3048)
			(end -0.508 -0.3048)
			(stroke
				(width 0.1)
				(type default)
			)
			(layer "B.Fab")
		)
		(fp_line
			(start 0.508 0.3048)
			(end -0.508 0.3048)
			(stroke
				(width 0.1)
				(type default)
			)
			(layer "B.Fab")
		)
		(fp_line
			(start -0.508 -0.3048)
			(end 0.508 -0.3048)
			(stroke
				(width 0.1)
				(type default)
			)
			(layer "B.Fab")
		)
		(fp_line
			(start 0.508 -0.3048)
			(end 0.508 0.3048)
			(stroke
				(width 0.1)
				(type default)
			)
			(layer "B.Fab")
		)
		(pad "1" smd rect
			(at 0.5334 0 90)
			(size 0.7112 0.6096)
			(layers "B.Cu" "B.Mask" "B.Paste")
			(net "XP3R3V_FPGA")
		)
		(pad "2" smd rect
			(at -0.5334 0 90)
			(size 0.7112 0.6096)
			(layers "B.Cu" "B.Mask" "B.Paste")
			(net "SHT3X_I2C_SDA")
		)
		(zone
			(layer "B.Cu")
			(hatch none 0.5)
			(connect_pads
				(clearance 0)
			)
			(min_thickness 0.25)
			(keepout
				(tracks allowed)
				(vias not_allowed)
				(pads allowed)
				(copperpour not_allowed)
				(footprints allowed)
			)
			(placement
				(enabled no)
				(sheetname "")
			)
			(fill
				(thermal_gap 0.5)
				(thermal_bridge_width 0.5)
				(island_removal_mode 0)
			)
			(polygon
				(pts
					(xy 150.038308 -48.93691) (xy 150.647908 -48.93691) (xy 150.647908 -49.08931) (xy 150.038308 -49.08931)
				)
			)
		)
	)
)
